(kicad_pcb
	(version 20260206)
	(generator "pcbnew")
	(generator_version "10.0")
	(general
		(thickness 1.6)
		(legacy_teardrops no)
	)
	(paper "A4")
	(title_block
		(title "Bryce Canyon_SCC_16316-1_OCP.brd")
		(comment 1 "Bryce Canyon / footprints 587-591 of 1561")
	)
	(layers
		(0 "F.Cu" signal "TOP")
		(4 "In1.Cu" signal "L2GND")
		(6 "In2.Cu" signal "L3")
		(8 "In3.Cu" signal "L4VCC")
		(10 "In4.Cu" signal "L5VCC")
		(12 "In5.Cu" signal "L6")
		(14 "In6.Cu" signal "L7GND")
		(2 "B.Cu" signal "BOTTOM")
		(9 "F.Adhes" user "F.Adhesive")
		(11 "B.Adhes" user "B.Adhesive")
		(13 "F.Paste" user "Package Geometry/Pastemask Top")
		(15 "B.Paste" user "Package Geometry/Pastemask Bottom")
		(5 "F.SilkS" user "Ref Des/Silkscreen Top")
		(7 "B.SilkS" user "Ref Des/Silkscreen Bottom")
		(1 "F.Mask" user "Board Geometry/Soldermask Top")
		(3 "B.Mask" user "Board Geometry/Soldermask Bottom")
		(17 "Dwgs.User" user "User.Drawings")
		(19 "Cmts.User" user "User.Comments")
		(21 "Eco1.User" user "User.Eco1")
		(23 "Eco2.User" user "User.Eco2")
		(25 "Edge.Cuts" user "Board Geometry/Outline")
		(27 "Margin" user)
		(31 "F.CrtYd" user "Package Geometry/Place Bound Top")
		(29 "B.CrtYd" user "Package Geometry/Place Bound Bottom")
		(35 "F.Fab" user "Ref Des/Assembly Top")
		(33 "B.Fab" user "Ref Des/Assembly Bottom")
	)
	(footprint ""
		(layer "F.Cu")
		(at 153.5176 -115.8494 90)
		(property "Reference" "U11"
			(at 0 0 90)
			(layer "F.SilkS")
			(hide yes)
			(effects
				(font
					(size 1.27 1.27)
				)
			)
		)
		(property "Value" "TPS53318DQPR-GP"
			(at -5.022088 -6.851904 90)
			(unlocked yes)
			(layer "F.Fab")
			(hide yes)
			(effects
				(font
					(size 1.016 1.016)
					(thickness 0.1524)
				)
			)
		)
		(property "Device Type" "DFN22G6050-G6133H60"
			(at -5.022088 -8.375904 90)
			(unlocked yes)
			(layer "F.Fab")
			(hide yes)
			(effects
				(font
					(size 1.016 1.016)
					(thickness 0.1524)
				)
			)
		)
		(duplicate_pad_numbers_are_jumpers no)
		(fp_line
			(start -2.2352 -3.5179)
			(end -3.5052 -3.5179)
			(stroke
				(width 0.1524)
				(type default)
			)
			(layer "F.SilkS")
		)
		(fp_line
			(start -3.5052 -3.5179)
			(end -3.5052 -2.2479)
			(stroke
				(width 0.1524)
				(type default)
			)
			(layer "F.SilkS")
		)
		(fp_line
			(start 0.500126 -3.262122)
			(end 0.500126 -3.770122)
			(stroke
				(width 0.1524)
				(type default)
			)
			(layer "F.SilkS")
		)
		(fp_line
			(start -1.999996 -3.262122)
			(end -1.999996 -4.024122)
			(stroke
				(width 0.1524)
				(type default)
			)
			(layer "F.SilkS")
		)
		(fp_line
			(start -3.5052 2.2479)
			(end -3.5052 3.5179)
			(stroke
				(width 0.1524)
				(type default)
			)
			(layer "F.SilkS")
		)
		(fp_line
			(start 1.500124 3.262122)
			(end 1.500124 4.024122)
			(stroke
				(width 0.1524)
				(type default)
			)
			(layer "F.SilkS")
		)
		(fp_line
			(start -0.999998 3.262122)
			(end -0.999998 3.770122)
			(stroke
				(width 0.1524)
				(type default)
			)
			(layer "F.SilkS")
		)
		(fp_line
			(start 3.5052 3.5179)
			(end 3.5052 2.2479)
			(stroke
				(width 0.1524)
				(type default)
			)
			(layer "F.SilkS")
		)
		(fp_line
			(start 2.2352 3.5179)
			(end 3.5052 3.5179)
			(stroke
				(width 0.1524)
				(type default)
			)
			(layer "F.SilkS")
		)
		(fp_line
			(start -3.5052 3.5179)
			(end -2.2352 3.5179)
			(stroke
				(width 0.1524)
				(type default)
			)
			(layer "F.SilkS")
		)
		(fp_poly
			(pts
				(xy 3.5052 -3.5179) (xy 2.4765 -3.5179) (xy 3.5052 -2.4892)
			)
			(stroke
				(width 0)
				(type default)
			)
			(fill yes)
			(layer "F.SilkS")
		)
		(fp_rect
			(start -2.9972 2.5019)
			(end 2.9972 -2.5019)
			(stroke
				(width 0)
				(type default)
			)
			(fill no)
			(layer "F.CrtYd")
		)
		(fp_poly
			(pts
				(xy 3.556 -2.5019) (xy -2.9972 -2.5019) (xy -2.9972 2.5019) (xy 2.9972 2.5019) (xy 2.9972 -2.4892)
				(xy 3.556 -2.4892) (xy 3.556 3.5179) (xy -3.556 3.5179) (xy -3.556 -3.5179) (xy 3.556 -3.5179)
			)
			(stroke
				(width 0)
				(type default)
			)
			(fill no)
			(layer "F.CrtYd")
		)
		(fp_rect
			(start -3.556 3.5179)
			(end 3.556 -3.5179)
			(stroke
				(width 0)
				(type default)
			)
			(fill no)
			(layer "F.Fab")
		)
		(pad "1" smd rect
			(at 2.500122 -2.449322 90)
			(size 0.3048 1.1176)
			(layers "F.Cu" "F.Mask" "F.Paste")
			(net "P1V5_E_VFB")
		)
		(pad "2" smd rect
			(at 1.999996 -2.449322 90)
			(size 0.3048 1.1176)
			(layers "F.Cu" "F.Mask" "F.Paste")
			(net "P1V5_E_EN")
		)
		(pad "3" smd rect
			(at 1.500124 -2.449322 90)
			(size 0.3048 1.1176)
			(layers "F.Cu" "F.Mask" "F.Paste")
			(net "P1V5_E_PG")
		)
		(pad "4" smd rect
			(at 0.999998 -2.449322 90)
			(size 0.3048 1.1176)
			(layers "F.Cu" "F.Mask" "F.Paste")
			(net "P1V5_E_VBST")
		)
		(pad "5" smd rect
			(at 0.500126 -2.449322 90)
			(size 0.3048 1.1176)
			(layers "F.Cu" "F.Mask" "F.Paste")
			(net "P1V5_E_ROVP")
		)
		(pad "6" smd rect
			(at 0 -2.449322 90)
			(size 0.3048 1.1176)
			(layers "F.Cu" "F.Mask" "F.Paste")
			(net "P1V5_E_LL")
		)
		(pad "7" smd rect
			(at -0.500126 -2.449322 90)
			(size 0.3048 1.1176)
			(layers "F.Cu" "F.Mask" "F.Paste")
			(net "P1V5_E_LL")
		)
		(pad "8" smd rect
			(at -0.999998 -2.449322 90)
			(size 0.3048 1.1176)
			(layers "F.Cu" "F.Mask" "F.Paste")
			(net "P1V5_E_LL")
		)
		(pad "9" smd rect
			(at -1.500124 -2.449322 90)
			(size 0.3048 1.1176)
			(layers "F.Cu" "F.Mask" "F.Paste")
			(net "P1V5_E_LL")
		)
		(pad "10" smd rect
			(at -1.999996 -2.449322 90)
			(size 0.3048 1.1176)
			(layers "F.Cu" "F.Mask" "F.Paste")
			(net "P1V5_E_LL")
		)
		(pad "11" smd rect
			(at -2.500122 -2.449322 90)
			(size 0.3048 1.1176)
			(layers "F.Cu" "F.Mask" "F.Paste")
			(net "P1V5_E_LL")
		)
		(pad "12" smd rect
			(at -2.500122 2.449322 90)
			(size 0.3048 1.1176)
			(layers "F.Cu" "F.Mask" "F.Paste")
			(net "P12V_STBY_VIN_U11")
		)
		(pad "13" smd rect
			(at -1.999996 2.449322 90)
			(size 0.3048 1.1176)
			(layers "F.Cu" "F.Mask" "F.Paste")
			(net "P12V_STBY_VIN_U11")
		)
		(pad "14" smd rect
			(at -1.500124 2.449322 90)
			(size 0.3048 1.1176)
			(layers "F.Cu" "F.Mask" "F.Paste")
			(net "P12V_STBY_VIN_U11")
		)
		(pad "15" smd rect
			(at -0.999998 2.449322 90)
			(size 0.3048 1.1176)
			(layers "F.Cu" "F.Mask" "F.Paste")
			(net "P12V_STBY_VIN_U11")
		)
		(pad "16" smd rect
			(at -0.500126 2.449322 90)
			(size 0.3048 1.1176)
			(layers "F.Cu" "F.Mask" "F.Paste")
			(net "P12V_STBY_VIN_U11")
		)
		(pad "17" smd rect
			(at 0 2.449322 90)
			(size 0.3048 1.1176)
			(layers "F.Cu" "F.Mask" "F.Paste")
			(net "P12V_STBY_VIN_U11")
		)
		(pad "18" smd rect
			(at 0.500126 2.449322 90)
			(size 0.3048 1.1176)
			(layers "F.Cu" "F.Mask" "F.Paste")
			(net "P1V5_E_VREG")
		)
		(pad "19" smd rect
			(at 0.999998 2.449322 90)
			(size 0.3048 1.1176)
			(layers "F.Cu" "F.Mask" "F.Paste")
			(net "P12V_STBY_VDD_U11")
		)
		(pad "20" smd rect
			(at 1.500124 2.449322 90)
			(size 0.3048 1.1176)
			(layers "F.Cu" "F.Mask" "F.Paste")
			(net "P1V5_E_MODE")
		)
		(pad "21" smd rect
			(at 1.999996 2.449322 90)
			(size 0.3048 1.1176)
			(layers "F.Cu" "F.Mask" "F.Paste")
			(net "P1V5_E_TRIP")
		)
		(pad "22" smd rect
			(at 2.500122 2.449322 90)
			(size 0.3048 1.1176)
			(layers "F.Cu" "F.Mask" "F.Paste")
			(net "P1V5_E_RF")
		)
		(pad "23" smd custom
			(at 0 0 90)
			(size 0.83185 0.83185)
			(layers "F.Cu" "F.Mask" "F.Paste")
			(net "GND")
			(options
				(clearance outline)
				(anchor circle)
			)
			(primitives
				(gr_poly
					(pts
						(xy -2.7813 1.6637) (xy -2.7813 1.2954) (xy -3.048 1.2954) (xy -3.048 0.9525) (xy -2.7813 0.9525)
						(xy -2.7813 -0.9525) (xy -3.048 -0.9525) (xy -3.048 -1.2954) (xy -2.7813 -1.2954) (xy -2.7813 -1.6637)
						(xy 2.7813 -1.6637) (xy 2.7813 -1.2954) (xy 3.048 -1.2954) (xy 3.048 -0.9525) (xy 2.7813 -0.9525)
						(xy 2.7813 0.9525) (xy 3.048 0.9525) (xy 3.048 1.2954) (xy 2.7813 1.2954) (xy 2.7813 1.6637)
					)
					(width 0)
					(fill yes)
				)
			)
		)
	)
	(footprint ""
		(layer "F.Cu")
		(at 128.00203 -44.732448 180)
		(property "Reference" "C45"
			(at 0 0 180)
			(layer "F.SilkS")
			(hide yes)
			(effects
				(font
					(size 1.27 1.27)
				)
			)
		)
		(property "Value" "SCD01U16V1KX-GP"
			(at -2.8321 -1.7399 180)
			(unlocked yes)
			(layer "F.Fab")
			(hide yes)
			(effects
				(font
					(size 1.016 1.016)
					(thickness 0.1524)
				)
			)
		)
		(property "Device Type" "C0201H13"
			(at -2.8321 -3.2639 180)
			(unlocked yes)
			(layer "F.Fab")
			(hide yes)
			(effects
				(font
					(size 1.016 1.016)
					(thickness 0.1524)
				)
			)
		)
		(duplicate_pad_numbers_are_jumpers no)
		(fp_rect
			(start -0.2794 0.6477)
			(end 0.2794 -0.6477)
			(stroke
				(width 0)
				(type default)
			)
			(fill no)
			(layer "F.CrtYd")
		)
		(fp_rect
			(start -0.2794 0.6477)
			(end 0.2794 -0.6477)
			(stroke
				(width 0)
				(type default)
			)
			(fill no)
			(layer "F.Fab")
		)
		(pad "1" smd custom
			(at 0 -0.2794 180)
			(size 0.0762 0.0762)
			(layers "F.Cu" "F.Mask" "F.Paste")
			(net "PHY_IOC_TO_SCC_41_DP")
			(options
				(clearance outline)
				(anchor circle)
			)
			(primitives
				(gr_poly
					(pts
						(arc
							(start 0.1524 -0.127)
							(mid 0.137521 -0.162921)
							(end 0.1016 -0.1778)
						)
						(arc
							(start -0.1016 -0.1778)
							(mid -0.137521 -0.162921)
							(end -0.1524 -0.127)
						)
						(arc
							(start -0.1524 0.127)
							(mid -0.137521 0.162921)
							(end -0.1016 0.1778)
						)
						(arc
							(start 0.1016 0.1778)
							(mid 0.137521 0.162921)
							(end 0.1524 0.127)
						)
					)
					(width 0)
					(fill yes)
				)
			)
		)
		(pad "2" smd custom
			(at 0 0.2794 180)
			(size 0.0762 0.0762)
			(layers "F.Cu" "F.Mask" "F.Paste")
			(net "PHY_IOC_TO_SCC_C_41_DP")
			(options
				(clearance outline)
				(anchor circle)
			)
			(primitives
				(gr_poly
					(pts
						(arc
							(start 0.1524 -0.127)
							(mid 0.137521 -0.162921)
							(end 0.1016 -0.1778)
						)
						(arc
							(start -0.1016 -0.1778)
							(mid -0.137521 -0.162921)
							(end -0.1524 -0.127)
						)
						(arc
							(start -0.1524 0.127)
							(mid -0.137521 0.162921)
							(end -0.1016 0.1778)
						)
						(arc
							(start 0.1016 0.1778)
							(mid 0.137521 0.162921)
							(end 0.1524 0.127)
						)
					)
					(width 0)
					(fill yes)
				)
			)
		)
	)
	(footprint ""
		(layer "F.Cu")
		(at 70.485 -62.484 90)
		(property "Reference" "R162"
			(at 0 0 90)
			(layer "F.SilkS")
			(hide yes)
			(effects
				(font
					(size 1.27 1.27)
				)
			)
		)
		(property "Value" "D51R3F-2-GP"
			(at -0.0254 -2.5146 90)
			(unlocked yes)
			(layer "F.Fab")
			(hide yes)
			(effects
				(font
					(size 1.016 1.016)
					(thickness 0.1524)
				)
			)
		)
		(property "Device Type" "R603H22"
			(at -0.0254 -4.0386 90)
			(unlocked yes)
			(layer "F.Fab")
			(hide yes)
			(effects
				(font
					(size 1.016 1.016)
					(thickness 0.1524)
				)
			)
		)
		(duplicate_pad_numbers_are_jumpers no)
		(fp_line
			(start 0.2032 0)
			(end 0.4826 0)
			(stroke
				(width 0.2032)
				(type default)
			)
			(layer "F.SilkS")
		)
		(fp_line
			(start -0.4826 0)
			(end -0.2032 0)
			(stroke
				(width 0.2032)
				(type default)
			)
			(layer "F.SilkS")
		)
		(fp_rect
			(start -0.5842 1.3335)
			(end 0.5842 -1.3335)
			(stroke
				(width 0)
				(type default)
			)
			(fill no)
			(layer "F.CrtYd")
		)
		(fp_rect
			(start -0.5842 1.3335)
			(end 0.5842 -1.3335)
			(stroke
				(width 0)
				(type default)
			)
			(fill no)
			(layer "F.Fab")
		)
		(pad "1" smd custom
			(at 0 -0.762 90)
			(size 0.2159 0.2159)
			(layers "F.Cu" "F.Mask" "F.Paste")
			(net "P0V9")
			(options
				(clearance outline)
				(anchor circle)
			)
			(primitives
				(gr_poly
					(pts
						(arc
							(start -0.3302 -0.4318)
							(mid -0.402042 -0.402042)
							(end -0.4318 -0.3302)
						)
						(arc
							(start -0.4318 0.3302)
							(mid -0.402042 0.402042)
							(end -0.3302 0.4318)
						)
						(arc
							(start 0.3302 0.4318)
							(mid 0.402042 0.402042)
							(end 0.4318 0.3302)
						)
						(arc
							(start 0.4318 -0.3302)
							(mid 0.402042 -0.402042)
							(end 0.3302 -0.4318)
						)
					)
					(width 0)
					(fill yes)
				)
			)
		)
		(pad "2" smd custom
			(at 0 0.762 90)
			(size 0.2159 0.2159)
			(layers "F.Cu" "F.Mask" "F.Paste")
			(net "GB_VDDA")
			(options
				(clearance outline)
				(anchor circle)
			)
			(primitives
				(gr_poly
					(pts
						(arc
							(start -0.3302 -0.4318)
							(mid -0.402042 -0.402042)
							(end -0.4318 -0.3302)
						)
						(arc
							(start -0.4318 0.3302)
							(mid -0.402042 0.402042)
							(end -0.3302 0.4318)
						)
						(arc
							(start 0.3302 0.4318)
							(mid 0.402042 0.402042)
							(end 0.4318 0.3302)
						)
						(arc
							(start 0.4318 -0.3302)
							(mid 0.402042 -0.402042)
							(end 0.3302 -0.4318)
						)
					)
					(width 0)
					(fill yes)
				)
			)
		)
	)
	(footprint ""
		(layer "F.Cu")
		(at 91.0082 -84.836 90)
		(property "Reference" "C112"
			(at 0 0 90)
			(layer "F.SilkS")
			(hide yes)
			(effects
				(font
					(size 1.27 1.27)
				)
			)
		)
		(property "Value" "SCD1U16V2KX-3GP"
			(at 1.1811 -2.7051 90)
			(unlocked yes)
			(layer "F.Fab")
			(hide yes)
			(effects
				(font
					(size 1.016 1.016)
					(thickness 0.1524)
				)
			)
		)
		(property "Device Type" "C402H22"
			(at 1.1811 -4.2291 90)
			(unlocked yes)
			(layer "F.Fab")
			(hide yes)
			(effects
				(font
					(size 1.016 1.016)
					(thickness 0.1524)
				)
			)
		)
		(duplicate_pad_numbers_are_jumpers no)
		(fp_rect
			(start -0.4318 0.9525)
			(end 0.4318 -0.9525)
			(stroke
				(width 0)
				(type default)
			)
			(fill no)
			(layer "F.CrtYd")
		)
		(fp_rect
			(start -0.4318 0.9525)
			(end 0.4318 -0.9525)
			(stroke
				(width 0)
				(type default)
			)
			(fill no)
			(layer "F.Fab")
		)
		(pad "1" smd custom
			(at 0 -0.4445 90)
			(size 0.1524 0.1524)
			(layers "F.Cu" "F.Mask" "F.Paste")
			(net "P3V3")
			(options
				(clearance outline)
				(anchor circle)
			)
			(primitives
				(gr_poly
					(pts
						(arc
							(start 0.3048 -0.2032)
							(mid 0.275042 -0.275042)
							(end 0.2032 -0.3048)
						)
						(arc
							(start -0.2032 -0.3048)
							(mid -0.275042 -0.275042)
							(end -0.3048 -0.2032)
						)
						(arc
							(start -0.3048 0.2032)
							(mid -0.275042 0.275042)
							(end -0.2032 0.3048)
						)
						(arc
							(start 0.2032 0.3048)
							(mid 0.275042 0.275042)
							(end 0.3048 0.2032)
						)
					)
					(width 0)
					(fill yes)
				)
			)
		)
		(pad "2" smd custom
			(at 0 0.4445 90)
			(size 0.1524 0.1524)
			(layers "F.Cu" "F.Mask" "F.Paste")
			(net "GND")
			(options
				(clearance outline)
				(anchor circle)
			)
			(primitives
				(gr_poly
					(pts
						(arc
							(start 0.3048 -0.2032)
							(mid 0.275042 -0.275042)
							(end 0.2032 -0.3048)
						)
						(arc
							(start -0.2032 -0.3048)
							(mid -0.275042 -0.275042)
							(end -0.3048 -0.2032)
						)
						(arc
							(start -0.3048 0.2032)
							(mid -0.275042 0.275042)
							(end -0.2032 0.3048)
						)
						(arc
							(start 0.2032 0.3048)
							(mid 0.275042 0.275042)
							(end 0.3048 0.2032)
						)
					)
					(width 0)
					(fill yes)
				)
			)
		)
	)
	(footprint ""
		(layer "F.Cu")
		(at 94.615 -87.503 -90)
		(property "Reference" "R306"
			(at 0 0 270)
			(layer "F.SilkS")
			(hide yes)
			(effects
				(font
					(size 1.27 1.27)
				)
			)
		)
		(property "Value" "10KR2F-2-GP"
			(at 0.064008 -3.993896 270)
			(unlocked yes)
			(layer "F.Fab")
			(hide yes)
			(effects
				(font
					(size 1.016 1.016)
					(thickness 0.1524)
				)
			)
		)
		(property "Device Type" "R402H16"
			(at 0.064008 -5.517896 270)
			(unlocked yes)
			(layer "F.Fab")
			(hide yes)
			(effects
				(font
					(size 1.016 1.016)
					(thickness 0.1524)
				)
			)
		)
		(duplicate_pad_numbers_are_jumpers no)
		(fp_line
			(start -0.508 -0.9398)
			(end -0.508 0.9398)
			(stroke
				(width 0.1524)
				(type default)
			)
			(layer "F.SilkS")
		)
		(fp_line
			(start 0.508 -0.9398)
			(end -0.508 -0.9398)
			(stroke
				(width 0.1524)
				(type default)
			)
			(layer "F.SilkS")
		)
		(fp_rect
			(start -0.508 0.9398)
			(end 0.508 -0.9398)
			(stroke
				(width 0)
				(type default)
			)
			(fill no)
			(layer "F.CrtYd")
		)
		(fp_rect
			(start -0.508 0.9398)
			(end 0.508 -0.9398)
			(stroke
				(width 0)
				(type default)
			)
			(fill no)
			(layer "F.Fab")
		)
		(pad "1" smd custom
			(at 0 -0.4445 270)
			(size 0.1397 0.1397)
			(layers "F.Cu" "F.Mask" "F.Paste")
			(net "BMC_RMT_HEARTBEAT_LS")
			(options
				(clearance outline)
				(anchor circle)
			)
			(primitives
				(gr_poly
					(pts
						(arc
							(start -0.1778 -0.2794)
							(mid -0.249642 -0.249642)
							(end -0.2794 -0.1778)
						)
						(arc
							(start -0.2794 0.1778)
							(mid -0.249642 0.249642)
							(end -0.1778 0.2794)
						)
						(arc
							(start 0.1778 0.2794)
							(mid 0.249642 0.249642)
							(end 0.2794 0.1778)
						)
						(arc
							(start 0.2794 -0.1778)
							(mid 0.249642 -0.249642)
							(end 0.1778 -0.2794)
						)
					)
					(width 0)
					(fill yes)
				)
			)
		)
		(pad "2" smd custom
			(at 0 0.4445 270)
			(size 0.1397 0.1397)
			(layers "F.Cu" "F.Mask" "F.Paste")
			(net "GND")
			(options
				(clearance outline)
				(anchor circle)
			)
			(primitives
				(gr_poly
					(pts
						(arc
							(start -0.1778 -0.2794)
							(mid -0.249642 -0.249642)
							(end -0.2794 -0.1778)
						)
						(arc
							(start -0.2794 0.1778)
							(mid -0.249642 0.249642)
							(end -0.1778 0.2794)
						)
						(arc
							(start 0.1778 0.2794)
							(mid 0.249642 0.249642)
							(end 0.2794 0.1778)
						)
						(arc
							(start 0.2794 -0.1778)
							(mid 0.249642 -0.249642)
							(end 0.1778 -0.2794)
						)
					)
					(width 0)
					(fill yes)
				)
			)
		)
	)
)
